# TIMECARD (Time Appliance Project (Time Card)) — schematic netlist excerpt (pin names and nets, part order shuffled) for the footprints in the layout excerpt that follows; sources: Cadence DE-HDL packaged netlist, KiCad conversion of R4006-B0001-02_R01.brd

R164  RESISTOR  100KOHM 1%  pkg SMC_0402R_H016  page 9 : \1\ = XP3R3V_FPGA ; \2\ = UNNAMED_3_RESISTOR_I151_2
C261  CAPACITOR  0.1UF 25V 10%  pkg SMC_0402R_H022  page 29 : \1\ = VIN_XP1R0V ; \2\ = SG

(kicad_pcb
	(version 20260206)
	(generator "pcbnew")
	(generator_version "10.0")
	(general
		(thickness 1.6)
		(legacy_teardrops no)
	)
	(paper "A4")
	(title_block
		(title "timecard-production-celestica-r4006 — R4006-B0001-02_R01.brd")
		(comment 1 "Time Appliance Project (Time Card) / footprints 637-638 of 1113")
	)
	(layers
		(0 "F.Cu" signal "TOP")
		(4 "In1.Cu" signal "L02_GND1")
		(6 "In2.Cu" signal "L03_SIG1")
		(8 "In3.Cu" signal "L04_GND2")
		(10 "In4.Cu" signal "L05_VCC1")
		(12 "In5.Cu" signal "L06_VCC2")
		(14 "In6.Cu" signal "L07_GND3")
		(16 "In7.Cu" signal "L08_SIG2")
		(18 "In8.Cu" signal "L09_GND4")
		(2 "B.Cu" signal "BOTTOM")
		(9 "F.Adhes" user "F.Adhesive")
		(11 "B.Adhes" user "B.Adhesive")
		(13 "F.Paste" user "Package Geometry/Pastemask Top")
		(15 "B.Paste" user "Package Geometry/Pastemask Bottom")
		(5 "F.SilkS" user "Ref Des/Silkscreen Top")
		(7 "B.SilkS" user "Ref Des/Silkscreen Bottom")
		(1 "F.Mask" user "Board Geometry/Soldermask Top")
		(3 "B.Mask" user "Board Geometry/Soldermask Bottom")
		(17 "Dwgs.User" user "User.Drawings")
		(19 "Cmts.User" user "User.Comments")
		(21 "Eco1.User" user "User.Eco1")
		(23 "Eco2.User" user "User.Eco2")
		(25 "Edge.Cuts" user "Board Geometry/Outline")
		(27 "Margin" user)
		(31 "F.CrtYd" user "Package Geometry/Place Bound Top")
		(29 "B.CrtYd" user "Package Geometry/Place Bound Bottom")
		(35 "F.Fab" user "Ref Des/Assembly Top")
		(33 "B.Fab" user "Ref Des/Assembly Bottom")
	)
	(footprint ""
		(layer "F.Cu")
		(at 95.504 -61.087 90)
		(property "Reference" "R164"
			(at -2.667 -0.08763 90)
			(unlocked yes)
			(layer "F.SilkS")
			(effects
				(font
					(size 0.7874 0.5842)
					(thickness 0.1524)
				)
			)
		)
		(property "Value" "VAL*"
			(at 0.02032 2.13233 90)
			(unlocked yes)
			(layer "F.Fab")
			(hide yes)
			(effects
				(font
					(size 0.7874 0.5842)
					(thickness 0.1524)
				)
			)
		)
		(property "Tolerance" "TOL*"
			(at 0.044704 3.05435 90)
			(unlocked yes)
			(layer "Cmts.User")
			(hide yes)
			(effects
				(font
					(size 0.7874 0.5842)
					(thickness 0.1524)
				)
			)
		)
		(property "User Part Number" "PARTNUM*"
			(at 0.02032 4.024884 90)
			(unlocked yes)
			(layer "Cmts.User")
			(hide yes)
			(effects
				(font
					(size 0.7874 0.5842)
					(thickness 0.1524)
				)
			)
		)
		(property "Device Type" "RESISTOR-G155-11003-01,100KOHMA"
			(at 0.008382 1.210564 90)
			(unlocked yes)
			(layer "F.Fab")
			(hide yes)
			(effects
				(font
					(size 0.7874 0.5842)
					(thickness 0.1524)
				)
			)
		)
		(duplicate_pad_numbers_are_jumpers no)
		(fp_line
			(start 1.143 -0.5588)
			(end -1.143 -0.5588)
			(stroke
				(width 0.1)
				(type default)
			)
			(layer "F.SilkS")
		)
		(fp_line
			(start -1.143 -0.5588)
			(end -1.143 0.5588)
			(stroke
				(width 0.1)
				(type default)
			)
			(layer "F.SilkS")
		)
		(fp_line
			(start 1.143 0.5588)
			(end 1.143 -0.5588)
			(stroke
				(width 0.1)
				(type default)
			)
			(layer "F.SilkS")
		)
		(fp_line
			(start -1.143 0.5588)
			(end 1.143 0.5588)
			(stroke
				(width 0.1)
				(type default)
			)
			(layer "F.SilkS")
		)
		(fp_poly
			(pts
				(xy -1.143 0.5588) (xy 1.143 0.5588) (xy 1.143 -0.5588) (xy -1.143 -0.5588)
			)
			(stroke
				(width 0)
				(type default)
			)
			(fill no)
			(layer "F.CrtYd")
		)
		(fp_line
			(start 0.508 -0.3048)
			(end -0.508 -0.3048)
			(stroke
				(width 0.1)
				(type default)
			)
			(layer "F.Fab")
		)
		(fp_line
			(start -0.508 -0.3048)
			(end -0.508 0.3048)
			(stroke
				(width 0.1)
				(type default)
			)
			(layer "F.Fab")
		)
		(fp_line
			(start 0.508 0.3048)
			(end 0.508 -0.3048)
			(stroke
				(width 0.1)
				(type default)
			)
			(layer "F.Fab")
		)
		(fp_line
			(start -0.508 0.3048)
			(end 0.508 0.3048)
			(stroke
				(width 0.1)
				(type default)
			)
			(layer "F.Fab")
		)
		(pad "1" smd rect
			(at -0.5334 0 90)
			(size 0.7112 0.6096)
			(layers "F.Cu" "F.Mask" "F.Paste")
			(net "XP3R3V_FPGA")
		)
		(pad "2" smd rect
			(at 0.5334 0 90)
			(size 0.7112 0.6096)
			(layers "F.Cu" "F.Mask" "F.Paste")
			(net "UNNAMED_3_RESISTOR_I151_2")
		)
		(zone
			(layer "F.Cu")
			(hatch none 0.5)
			(connect_pads
				(clearance 0)
			)
			(min_thickness 0.25)
			(keepout
				(tracks allowed)
				(vias not_allowed)
				(pads allowed)
				(copperpour not_allowed)
				(footprints allowed)
			)
			(placement
				(enabled no)
				(sheetname "")
			)
			(fill
				(thermal_gap 0.5)
				(thermal_bridge_width 0.5)
				(island_removal_mode 0)
			)
			(polygon
				(pts
					(xy 95.8088 -61.0108) (xy 95.8088 -61.1632) (xy 95.1992 -61.1632) (xy 95.1992 -61.0108)
				)
			)
		)
		(zone
			(layer "F.Cu")
			(hatch none 0.5)
			(connect_pads
				(clearance 0)
			)
			(min_thickness 0.25)
			(keepout
				(tracks not_allowed)
				(vias allowed)
				(pads allowed)
				(copperpour not_allowed)
				(footprints allowed)
			)
			(placement
				(enabled no)
				(sheetname "")
			)
			(fill
				(thermal_gap 0.5)
				(thermal_bridge_width 0.5)
				(island_removal_mode 0)
			)
			(polygon
				(pts
					(xy 95.8088 -61.0108) (xy 95.8088 -61.1632) (xy 95.1992 -61.1632) (xy 95.1992 -61.0108)
				)
			)
		)
	)
	(footprint ""
		(layer "F.Cu")
		(at 138.43 -53.594 -90)
		(property "Reference" "C261"
			(at 0.508 3.26263 90)
			(unlocked yes)
			(layer "F.SilkS")
			(effects
				(font
					(size 0.7874 0.5842)
					(thickness 0.1524)
				)
			)
		)
		(property "Value" "VAL*"
			(at 0.0762 2.067306 270)
			(unlocked yes)
			(layer "F.Fab")
			(hide yes)
			(effects
				(font
					(size 0.7874 0.5842)
					(thickness 0.1524)
				)
			)
		)
		(property "Device Type" "CAPACITOR-G105-0B104-EK,0.1UF,A"
			(at 0.0508 1.127506 270)
			(unlocked yes)
			(layer "F.Fab")
			(hide yes)
			(effects
				(font
					(size 0.7874 0.5842)
					(thickness 0.1524)
				)
			)
		)
		(property "User Part Number" "PARTNUM*"
			(at 0.1016 4.023106 270)
			(unlocked yes)
			(layer "Cmts.User")
			(hide yes)
			(effects
				(font
					(size 0.7874 0.5842)
					(thickness 0.1524)
				)
			)
		)
		(property "Tolerance" "TOL*"
			(at 0.0762 3.032506 270)
			(unlocked yes)
			(layer "Cmts.User")
			(hide yes)
			(effects
				(font
					(size 0.7874 0.5842)
					(thickness 0.1524)
				)
			)
		)
		(duplicate_pad_numbers_are_jumpers no)
		(fp_line
			(start -1.143 0.5588)
			(end 1.143 0.5588)
			(stroke
				(width 0.1)
				(type default)
			)
			(layer "F.SilkS")
		)
		(fp_line
			(start 1.143 0.5588)
			(end 1.143 -0.5588)
			(stroke
				(width 0.1)
				(type default)
			)
			(layer "F.SilkS")
		)
		(fp_line
			(start -1.143 -0.5588)
			(end -1.143 0.5588)
			(stroke
				(width 0.1)
				(type default)
			)
			(layer "F.SilkS")
		)
		(fp_line
			(start 1.143 -0.5588)
			(end -1.143 -0.5588)
			(stroke
				(width 0.1)
				(type default)
			)
			(layer "F.SilkS")
		)
		(fp_rect
			(start 1.143 0.5588)
			(end -1.143 -0.5588)
			(stroke
				(width 0)
				(type default)
			)
			(fill no)
			(layer "F.CrtYd")
		)
		(fp_line
			(start -0.508 0.3048)
			(end 0.508 0.3048)
			(stroke
				(width 0.1)
				(type default)
			)
			(layer "F.Fab")
		)
		(fp_line
			(start 0.508 0.3048)
			(end 0.508 -0.3048)
			(stroke
				(width 0.1)
				(type default)
			)
			(layer "F.Fab")
		)
		(fp_line
			(start -0.508 -0.3048)
			(end -0.508 0.3048)
			(stroke
				(width 0.1)
				(type default)
			)
			(layer "F.Fab")
		)
		(fp_line
			(start 0.508 -0.3048)
			(end -0.508 -0.3048)
			(stroke
				(width 0.1)
				(type default)
			)
			(layer "F.Fab")
		)
		(pad "1" smd rect
			(at -0.5334 0 270)
			(size 0.7112 0.6096)
			(layers "F.Cu" "F.Mask" "F.Paste")
			(net "VIN_XP1R0V")
		)
		(pad "2" smd rect
			(at 0.5334 0 270)
			(size 0.7112 0.6096)
			(layers "F.Cu" "F.Mask" "F.Paste")
			(net "SG")
		)
		(zone
			(layer "F.Cu")
			(hatch none 0.5)
			(connect_pads
				(clearance 0)
			)
			(min_thickness 0.25)
			(keepout
				(tracks allowed)
				(vias not_allowed)
				(pads allowed)
				(copperpour not_allowed)
				(footprints allowed)
			)
			(placement
				(enabled no)
				(sheetname "")
			)
			(fill
				(thermal_gap 0.5)
				(thermal_bridge_width 0.5)
				(island_removal_mode 0)
			)
			(polygon
				(pts
					(xy 138.1252 -53.5178) (xy 138.7348 -53.5178) (xy 138.7348 -53.6702) (xy 138.1252 -53.6702)
				)
			)
		)
	)
)
